FILE_TYPE=LIBRARY_PARTS;
primitive 'SW20S_DHNF10FQTR';
  pin
    '1':
      PIN_NUMBER='(1)';
      BIDIRECTIONAL='TRUE';
      INPUT_LOAD='(-0.01,0.01)';
      OUTPUT_LOAD='(1.0,-1.0)';
    '2':
      PIN_NUMBER='(2)';
      BIDIRECTIONAL='TRUE';
      INPUT_LOAD='(-0.01,0.01)';
      OUTPUT_LOAD='(1.0,-1.0)';
    '3':
      PIN_NUMBER='(3)';
      BIDIRECTIONAL='TRUE';
      INPUT_LOAD='(-0.01,0.01)';
      OUTPUT_LOAD='(1.0,-1.0)';
    '4':
      PIN_NUMBER='(4)';
      BIDIRECTIONAL='TRUE';
      INPUT_LOAD='(-0.01,0.01)';
      OUTPUT_LOAD='(1.0,-1.0)';
    '11':
      PIN_NUMBER='(11)';
      BIDIRECTIONAL='TRUE';
      INPUT_LOAD='(-0.01,0.01)';
      OUTPUT_LOAD='(1.0,-1.0)';
    '12':
      PIN_NUMBER='(12)';
      BIDIRECTIONAL='TRUE';
      INPUT_LOAD='(-0.01,0.01)';
      OUTPUT_LOAD='(1.0,-1.0)';
    '13':
      PIN_NUMBER='(13)';
      BIDIRECTIONAL='TRUE';
      INPUT_LOAD='(-0.01,0.01)';
      OUTPUT_LOAD='(1.0,-1.0)';
    '14':
      PIN_NUMBER='(14)';
      BIDIRECTIONAL='TRUE';
      INPUT_LOAD='(-0.01,0.01)';
      OUTPUT_LOAD='(1.0,-1.0)';
    '5':
      PIN_NUMBER='(5)';
      BIDIRECTIONAL='TRUE';
      INPUT_LOAD='(-0.01,0.01)';
      OUTPUT_LOAD='(1.0,-1.0)';
    '6':
      PIN_NUMBER='(6)';
      BIDIRECTIONAL='TRUE';
      INPUT_LOAD='(-0.01,0.01)';
      OUTPUT_LOAD='(1.0,-1.0)';
    '7':
      PIN_NUMBER='(7)';
      BIDIRECTIONAL='TRUE';
      INPUT_LOAD='(-0.01,0.01)';
      OUTPUT_LOAD='(1.0,-1.0)';
    '8':
      PIN_NUMBER='(8)';
      BIDIRECTIONAL='TRUE';
      INPUT_LOAD='(-0.01,0.01)';
      OUTPUT_LOAD='(1.0,-1.0)';
    '15':
      PIN_NUMBER='(15)';
      BIDIRECTIONAL='TRUE';
      INPUT_LOAD='(-0.01,0.01)';
      OUTPUT_LOAD='(1.0,-1.0)';
    '16':
      PIN_NUMBER='(16)';
      BIDIRECTIONAL='TRUE';
      INPUT_LOAD='(-0.01,0.01)';
      OUTPUT_LOAD='(1.0,-1.0)';
    '17':
      PIN_NUMBER='(17)';
      BIDIRECTIONAL='TRUE';
      INPUT_LOAD='(-0.01,0.01)';
      OUTPUT_LOAD='(1.0,-1.0)';
    '18':
      PIN_NUMBER='(18)';
      BIDIRECTIONAL='TRUE';
      INPUT_LOAD='(-0.01,0.01)';
      OUTPUT_LOAD='(1.0,-1.0)';
    '19':
      PIN_NUMBER='(19)';
      BIDIRECTIONAL='TRUE';
      INPUT_LOAD='(-0.01,0.01)';
      OUTPUT_LOAD='(1.0,-1.0)';
    '20':
      PIN_NUMBER='(20)';
      BIDIRECTIONAL='TRUE';
      INPUT_LOAD='(-0.01,0.01)';
      OUTPUT_LOAD='(1.0,-1.0)';
    '9':
      PIN_NUMBER='(9)';
      BIDIRECTIONAL='TRUE';
      INPUT_LOAD='(-0.01,0.01)';
      OUTPUT_LOAD='(1.0,-1.0)';
    '10':
      PIN_NUMBER='(10)';
      BIDIRECTIONAL='TRUE';
      INPUT_LOAD='(-0.01,0.01)';
      OUTPUT_LOAD='(1.0,-1.0)';
  end_pin;
  body
    PART_NAME='SW20S_DHNF10FQTR';
    BODY_NAME='SW20S_DHNF10FQTR';
    PHYS_DES_PREFIX='SW';
    CLASS='IO';
  end_body;
end_primitive;

END.
